(kicad_pcb
	(version 20260206)
	(generator "pcbnew")
	(generator_version "10.0")
	(general
		(thickness 1.6)
		(legacy_teardrops no)
	)
	(paper "A4")
	(title_block
		(title "Bryce Canyon_IOM_IOC_16318-2_OCP.brd")
		(comment 1 "Bryce Canyon / footprints 1073-1080 of 1605")
	)
	(layers
		(0 "F.Cu" signal "TOP")
		(4 "In1.Cu" signal "L2GND")
		(6 "In2.Cu" signal "L3")
		(8 "In3.Cu" signal "L4VCC")
		(10 "In4.Cu" signal "L5VCC")
		(12 "In5.Cu" signal "L6")
		(14 "In6.Cu" signal "L7GND")
		(2 "B.Cu" signal "BOTTOM")
		(9 "F.Adhes" user "F.Adhesive")
		(11 "B.Adhes" user "B.Adhesive")
		(13 "F.Paste" user "Package Geometry/Pastemask Top")
		(15 "B.Paste" user "Package Geometry/Pastemask Bottom")
		(5 "F.SilkS" user "Ref Des/Silkscreen Top")
		(7 "B.SilkS" user "Ref Des/Silkscreen Bottom")
		(1 "F.Mask" user "Board Geometry/Soldermask Top")
		(3 "B.Mask" user "Board Geometry/Soldermask Bottom")
		(17 "Dwgs.User" user "User.Drawings")
		(19 "Cmts.User" user "User.Comments")
		(21 "Eco1.User" user "User.Eco1")
		(23 "Eco2.User" user "User.Eco2")
		(25 "Edge.Cuts" user "Board Geometry/Outline")
		(27 "Margin" user)
		(31 "F.CrtYd" user "Package Geometry/Place Bound Top")
		(29 "B.CrtYd" user "Package Geometry/Place Bound Bottom")
		(35 "F.Fab" user "Ref Des/Assembly Top")
		(33 "B.Fab" user "Ref Des/Assembly Bottom")
	)
	(footprint ""
		(layer "B.Cu")
		(at 184.023 -66.6242 90)
		(property "Reference" "C474"
			(at 0 0 90)
			(layer "B.SilkS")
			(hide yes)
			(effects
				(font
					(size 1.27 1.27)
				)
				(justify mirror)
			)
		)
		(property "Value" "SC1KP50V2KX-1GP"
			(at -1.1811 -2.7051 90)
			(unlocked yes)
			(layer "B.Fab")
			(hide yes)
			(effects
				(font
					(size 1.016 1.016)
					(thickness 0.1524)
				)
				(justify mirror)
			)
		)
		(property "Device Type" "C402H22"
			(at -1.1811 -4.2291 90)
			(unlocked yes)
			(layer "B.Fab")
			(hide yes)
			(effects
				(font
					(size 1.016 1.016)
					(thickness 0.1524)
				)
				(justify mirror)
			)
		)
		(duplicate_pad_numbers_are_jumpers no)
		(fp_rect
			(start 0.4318 0.9525)
			(end -0.4318 -0.9525)
			(stroke
				(width 0)
				(type default)
			)
			(fill no)
			(layer "B.CrtYd")
		)
		(fp_rect
			(start 0.4318 0.9525)
			(end -0.4318 -0.9525)
			(stroke
				(width 0)
				(type default)
			)
			(fill no)
			(layer "B.Fab")
		)
		(pad "1" smd custom
			(at 0 -0.4445 270)
			(size 0.1524 0.1524)
			(layers "B.Cu" "B.Mask" "B.Paste")
			(net "P1V8")
			(options
				(clearance outline)
				(anchor circle)
			)
			(primitives
				(gr_poly
					(pts
						(arc
							(start 0.3048 0.2032)
							(mid 0.275042 0.275042)
							(end 0.2032 0.3048)
						)
						(arc
							(start -0.2032 0.3048)
							(mid -0.275042 0.275042)
							(end -0.3048 0.2032)
						)
						(arc
							(start -0.3048 -0.2032)
							(mid -0.275042 -0.275042)
							(end -0.2032 -0.3048)
						)
						(arc
							(start 0.2032 -0.3048)
							(mid 0.275042 -0.275042)
							(end 0.3048 -0.2032)
						)
					)
					(width 0)
					(fill yes)
				)
			)
		)
		(pad "2" smd custom
			(at 0 0.4445 270)
			(size 0.1524 0.1524)
			(layers "B.Cu" "B.Mask" "B.Paste")
			(net "GND")
			(options
				(clearance outline)
				(anchor circle)
			)
			(primitives
				(gr_poly
					(pts
						(arc
							(start 0.3048 0.2032)
							(mid 0.275042 0.275042)
							(end 0.2032 0.3048)
						)
						(arc
							(start -0.2032 0.3048)
							(mid -0.275042 0.275042)
							(end -0.3048 0.2032)
						)
						(arc
							(start -0.3048 -0.2032)
							(mid -0.275042 -0.275042)
							(end -0.2032 -0.3048)
						)
						(arc
							(start 0.2032 -0.3048)
							(mid 0.275042 -0.275042)
							(end 0.3048 -0.2032)
						)
					)
					(width 0)
					(fill yes)
				)
			)
		)
	)
	(footprint ""
		(layer "B.Cu")
		(at 50.75682 -148.19376 -90)
		(property "Reference" "C101"
			(at 0 0 90)
			(layer "B.SilkS")
			(hide yes)
			(effects
				(font
					(size 1.27 1.27)
				)
				(justify mirror)
			)
		)
		(property "Value" "SC1U16V3KX-5GP"
			(at 0 -2.8194 270)
			(unlocked yes)
			(layer "B.Fab")
			(hide yes)
			(effects
				(font
					(size 1.016 1.016)
					(thickness 0.1524)
				)
				(justify mirror)
			)
		)
		(property "Device Type" "C603H36"
			(at 0 -4.3434 270)
			(unlocked yes)
			(layer "B.Fab")
			(hide yes)
			(effects
				(font
					(size 1.016 1.016)
					(thickness 0.1524)
				)
				(justify mirror)
			)
		)
		(duplicate_pad_numbers_are_jumpers no)
		(fp_line
			(start -0.508 0)
			(end 0.508 0)
			(stroke
				(width 0.2032)
				(type default)
			)
			(layer "B.SilkS")
		)
		(fp_rect
			(start 0.5842 1.3335)
			(end -0.5842 -1.3335)
			(stroke
				(width 0)
				(type default)
			)
			(fill no)
			(layer "B.CrtYd")
		)
		(fp_rect
			(start 0.5842 1.3335)
			(end -0.5842 -1.3335)
			(stroke
				(width 0)
				(type default)
			)
			(fill no)
			(layer "B.Fab")
		)
		(pad "1" smd custom
			(at 0 -0.762 90)
			(size 0.2159 0.2159)
			(layers "B.Cu" "B.Mask" "B.Paste")
			(net "P3V3_STBY")
			(options
				(clearance outline)
				(anchor circle)
			)
			(primitives
				(gr_poly
					(pts
						(arc
							(start -0.3302 0.4318)
							(mid -0.402042 0.402042)
							(end -0.4318 0.3302)
						)
						(arc
							(start -0.4318 -0.3302)
							(mid -0.402042 -0.402042)
							(end -0.3302 -0.4318)
						)
						(arc
							(start 0.3302 -0.4318)
							(mid 0.402042 -0.402042)
							(end 0.4318 -0.3302)
						)
						(arc
							(start 0.4318 0.3302)
							(mid 0.402042 0.402042)
							(end 0.3302 0.4318)
						)
					)
					(width 0)
					(fill yes)
				)
			)
		)
		(pad "2" smd custom
			(at 0 0.762 90)
			(size 0.2159 0.2159)
			(layers "B.Cu" "B.Mask" "B.Paste")
			(net "GND")
			(options
				(clearance outline)
				(anchor circle)
			)
			(primitives
				(gr_poly
					(pts
						(arc
							(start -0.3302 0.4318)
							(mid -0.402042 0.402042)
							(end -0.4318 0.3302)
						)
						(arc
							(start -0.4318 -0.3302)
							(mid -0.402042 -0.402042)
							(end -0.3302 -0.4318)
						)
						(arc
							(start 0.3302 -0.4318)
							(mid 0.402042 -0.402042)
							(end 0.4318 -0.3302)
						)
						(arc
							(start 0.4318 0.3302)
							(mid 0.402042 0.402042)
							(end 0.3302 0.4318)
						)
					)
					(width 0)
					(fill yes)
				)
			)
		)
	)
	(footprint ""
		(layer "B.Cu")
		(at 207.3148 -79.9084 90)
		(property "Reference" "R349"
			(at 0 0 90)
			(layer "B.SilkS")
			(hide yes)
			(effects
				(font
					(size 1.27 1.27)
				)
				(justify mirror)
			)
		)
		(property "Value" "0R2J-2-GP"
			(at -0.064008 -3.993896 90)
			(unlocked yes)
			(layer "B.Fab")
			(hide yes)
			(effects
				(font
					(size 1.016 1.016)
					(thickness 0.1524)
				)
				(justify mirror)
			)
		)
		(property "Device Type" "R402H16"
			(at -0.064008 -5.517896 90)
			(unlocked yes)
			(layer "B.Fab")
			(hide yes)
			(effects
				(font
					(size 1.016 1.016)
					(thickness 0.1524)
				)
				(justify mirror)
			)
		)
		(duplicate_pad_numbers_are_jumpers no)
		(fp_line
			(start 0.508 -0.9398)
			(end 0.508 0.9398)
			(stroke
				(width 0.1524)
				(type default)
			)
			(layer "B.SilkS")
		)
		(fp_line
			(start -0.508 -0.9398)
			(end 0.508 -0.9398)
			(stroke
				(width 0.1524)
				(type default)
			)
			(layer "B.SilkS")
		)
		(fp_rect
			(start 0.508 0.9398)
			(end -0.508 -0.9398)
			(stroke
				(width 0)
				(type default)
			)
			(fill no)
			(layer "B.CrtYd")
		)
		(fp_rect
			(start 0.508 0.9398)
			(end -0.508 -0.9398)
			(stroke
				(width 0)
				(type default)
			)
			(fill no)
			(layer "B.Fab")
		)
		(pad "1" smd custom
			(at 0 -0.4445 270)
			(size 0.1397 0.1397)
			(layers "B.Cu" "B.Mask" "B.Paste")
			(net "P0V975")
			(options
				(clearance outline)
				(anchor circle)
			)
			(primitives
				(gr_poly
					(pts
						(arc
							(start -0.1778 0.2794)
							(mid -0.249642 0.249642)
							(end -0.2794 0.1778)
						)
						(arc
							(start -0.2794 -0.1778)
							(mid -0.249642 -0.249642)
							(end -0.1778 -0.2794)
						)
						(arc
							(start 0.1778 -0.2794)
							(mid 0.249642 -0.249642)
							(end 0.2794 -0.1778)
						)
						(arc
							(start 0.2794 0.1778)
							(mid 0.249642 0.249642)
							(end 0.1778 0.2794)
						)
					)
					(width 0)
					(fill yes)
				)
			)
		)
		(pad "2" smd custom
			(at 0 0.4445 270)
			(size 0.1397 0.1397)
			(layers "B.Cu" "B.Mask" "B.Paste")
			(net "P0V975_SEN")
			(options
				(clearance outline)
				(anchor circle)
			)
			(primitives
				(gr_poly
					(pts
						(arc
							(start -0.1778 0.2794)
							(mid -0.249642 0.249642)
							(end -0.2794 0.1778)
						)
						(arc
							(start -0.2794 -0.1778)
							(mid -0.249642 -0.249642)
							(end -0.1778 -0.2794)
						)
						(arc
							(start 0.1778 -0.2794)
							(mid 0.249642 -0.249642)
							(end 0.2794 -0.1778)
						)
						(arc
							(start 0.2794 0.1778)
							(mid 0.249642 0.249642)
							(end 0.1778 0.2794)
						)
					)
					(width 0)
					(fill yes)
				)
			)
		)
	)
	(footprint ""
		(layer "B.Cu")
		(at 81.026 -140.4366 -90)
		(property "Reference" "R720"
			(at 0 0 90)
			(layer "B.SilkS")
			(hide yes)
			(effects
				(font
					(size 1.27 1.27)
				)
				(justify mirror)
			)
		)
		(property "Value" "0R2J-2-GP"
			(at -0.064008 -3.993896 270)
			(unlocked yes)
			(layer "B.Fab")
			(hide yes)
			(effects
				(font
					(size 1.016 1.016)
					(thickness 0.1524)
				)
				(justify mirror)
			)
		)
		(property "Device Type" "R402H16"
			(at -0.064008 -5.517896 270)
			(unlocked yes)
			(layer "B.Fab")
			(hide yes)
			(effects
				(font
					(size 1.016 1.016)
					(thickness 0.1524)
				)
				(justify mirror)
			)
		)
		(duplicate_pad_numbers_are_jumpers no)
		(fp_line
			(start -0.508 -0.9398)
			(end 0.508 -0.9398)
			(stroke
				(width 0.1524)
				(type default)
			)
			(layer "B.SilkS")
		)
		(fp_line
			(start 0.508 -0.9398)
			(end 0.508 0.9398)
			(stroke
				(width 0.1524)
				(type default)
			)
			(layer "B.SilkS")
		)
		(fp_rect
			(start 0.508 0.9398)
			(end -0.508 -0.9398)
			(stroke
				(width 0)
				(type default)
			)
			(fill no)
			(layer "B.CrtYd")
		)
		(fp_rect
			(start 0.508 0.9398)
			(end -0.508 -0.9398)
			(stroke
				(width 0)
				(type default)
			)
			(fill no)
			(layer "B.Fab")
		)
		(pad "1" smd custom
			(at 0 -0.4445 90)
			(size 0.1397 0.1397)
			(layers "B.Cu" "B.Mask" "B.Paste")
			(net "PWRGD_P3V3_STBY_N")
			(options
				(clearance outline)
				(anchor circle)
			)
			(primitives
				(gr_poly
					(pts
						(arc
							(start -0.1778 0.2794)
							(mid -0.249642 0.249642)
							(end -0.2794 0.1778)
						)
						(arc
							(start -0.2794 -0.1778)
							(mid -0.249642 -0.249642)
							(end -0.1778 -0.2794)
						)
						(arc
							(start 0.1778 -0.2794)
							(mid 0.249642 -0.249642)
							(end 0.2794 -0.1778)
						)
						(arc
							(start 0.2794 0.1778)
							(mid 0.249642 0.249642)
							(end 0.1778 0.2794)
						)
					)
					(width 0)
					(fill yes)
				)
			)
		)
		(pad "2" smd custom
			(at 0 0.4445 90)
			(size 0.1397 0.1397)
			(layers "B.Cu" "B.Mask" "B.Paste")
			(net "PWRGD_P3V3_STBY_N_R1")
			(options
				(clearance outline)
				(anchor circle)
			)
			(primitives
				(gr_poly
					(pts
						(arc
							(start -0.1778 0.2794)
							(mid -0.249642 0.249642)
							(end -0.2794 0.1778)
						)
						(arc
							(start -0.2794 -0.1778)
							(mid -0.249642 -0.249642)
							(end -0.1778 -0.2794)
						)
						(arc
							(start 0.1778 -0.2794)
							(mid 0.249642 -0.249642)
							(end 0.2794 -0.1778)
						)
						(arc
							(start 0.2794 0.1778)
							(mid 0.249642 0.249642)
							(end 0.1778 0.2794)
						)
					)
					(width 0)
					(fill yes)
				)
			)
		)
	)
	(footprint ""
		(layer "B.Cu")
		(at 166.79291 -76.242164)
		(property "Reference" "R676"
			(at 0 0 0)
			(layer "B.SilkS")
			(hide yes)
			(effects
				(font
					(size 1.27 1.27)
				)
				(justify mirror)
			)
		)
		(property "Value" "10KR2F-2-GP"
			(at -0.064008 -3.993896 0)
			(unlocked yes)
			(layer "B.Fab")
			(hide yes)
			(effects
				(font
					(size 1.016 1.016)
					(thickness 0.1524)
				)
				(justify mirror)
			)
		)
		(property "Device Type" "R402H16"
			(at -0.064008 -5.517896 0)
			(unlocked yes)
			(layer "B.Fab")
			(hide yes)
			(effects
				(font
					(size 1.016 1.016)
					(thickness 0.1524)
				)
				(justify mirror)
			)
		)
		(duplicate_pad_numbers_are_jumpers no)
		(fp_line
			(start -0.508 -0.9398)
			(end 0.508 -0.9398)
			(stroke
				(width 0.1524)
				(type default)
			)
			(layer "B.SilkS")
		)
		(fp_line
			(start 0.508 -0.9398)
			(end 0.508 0.9398)
			(stroke
				(width 0.1524)
				(type default)
			)
			(layer "B.SilkS")
		)
		(fp_rect
			(start 0.508 0.9398)
			(end -0.508 -0.9398)
			(stroke
				(width 0)
				(type default)
			)
			(fill no)
			(layer "B.CrtYd")
		)
		(fp_rect
			(start 0.508 0.9398)
			(end -0.508 -0.9398)
			(stroke
				(width 0)
				(type default)
			)
			(fill no)
			(layer "B.Fab")
		)
		(pad "1" smd custom
			(at 0 -0.4445 180)
			(size 0.1397 0.1397)
			(layers "B.Cu" "B.Mask" "B.Paste")
			(net "P1V8")
			(options
				(clearance outline)
				(anchor circle)
			)
			(primitives
				(gr_poly
					(pts
						(arc
							(start -0.1778 0.2794)
							(mid -0.249642 0.249642)
							(end -0.2794 0.1778)
						)
						(arc
							(start -0.2794 -0.1778)
							(mid -0.249642 -0.249642)
							(end -0.1778 -0.2794)
						)
						(arc
							(start 0.1778 -0.2794)
							(mid 0.249642 -0.249642)
							(end 0.2794 -0.1778)
						)
						(arc
							(start 0.2794 0.1778)
							(mid 0.249642 0.249642)
							(end 0.1778 0.2794)
						)
					)
					(width 0)
					(fill yes)
				)
			)
		)
		(pad "2" smd custom
			(at 0 0.4445 180)
			(size 0.1397 0.1397)
			(layers "B.Cu" "B.Mask" "B.Paste")
			(net "IOC_WP_N")
			(options
				(clearance outline)
				(anchor circle)
			)
			(primitives
				(gr_poly
					(pts
						(arc
							(start -0.1778 0.2794)
							(mid -0.249642 0.249642)
							(end -0.2794 0.1778)
						)
						(arc
							(start -0.2794 -0.1778)
							(mid -0.249642 -0.249642)
							(end -0.1778 -0.2794)
						)
						(arc
							(start 0.1778 -0.2794)
							(mid 0.249642 -0.249642)
							(end 0.2794 -0.1778)
						)
						(arc
							(start 0.2794 0.1778)
							(mid 0.249642 0.249642)
							(end 0.1778 0.2794)
						)
					)
					(width 0)
					(fill yes)
				)
			)
		)
	)
	(footprint ""
		(layer "B.Cu")
		(at 87.837518 -146.263614 -90)
		(property "Reference" "R424"
			(at 0 0 90)
			(layer "B.SilkS")
			(hide yes)
			(effects
				(font
					(size 1.27 1.27)
				)
				(justify mirror)
			)
		)
		(property "Value" "4K7R2F-GP"
			(at -0.064008 -3.993896 270)
			(unlocked yes)
			(layer "B.Fab")
			(hide yes)
			(effects
				(font
					(size 1.016 1.016)
					(thickness 0.1524)
				)
				(justify mirror)
			)
		)
		(property "Device Type" "R402H16"
			(at -0.064008 -5.517896 270)
			(unlocked yes)
			(layer "B.Fab")
			(hide yes)
			(effects
				(font
					(size 1.016 1.016)
					(thickness 0.1524)
				)
				(justify mirror)
			)
		)
		(duplicate_pad_numbers_are_jumpers no)
		(fp_line
			(start -0.508 -0.9398)
			(end 0.508 -0.9398)
			(stroke
				(width 0.1524)
				(type default)
			)
			(layer "B.SilkS")
		)
		(fp_line
			(start 0.508 -0.9398)
			(end 0.508 0.9398)
			(stroke
				(width 0.1524)
				(type default)
			)
			(layer "B.SilkS")
		)
		(fp_rect
			(start 0.508 0.9398)
			(end -0.508 -0.9398)
			(stroke
				(width 0)
				(type default)
			)
			(fill no)
			(layer "B.CrtYd")
		)
		(fp_rect
			(start 0.508 0.9398)
			(end -0.508 -0.9398)
			(stroke
				(width 0)
				(type default)
			)
			(fill no)
			(layer "B.Fab")
		)
		(pad "1" smd custom
			(at 0 -0.4445 90)
			(size 0.1397 0.1397)
			(layers "B.Cu" "B.Mask" "B.Paste")
			(net "P3V3_STBY")
			(options
				(clearance outline)
				(anchor circle)
			)
			(primitives
				(gr_poly
					(pts
						(arc
							(start -0.1778 0.2794)
							(mid -0.249642 0.249642)
							(end -0.2794 0.1778)
						)
						(arc
							(start -0.2794 -0.1778)
							(mid -0.249642 -0.249642)
							(end -0.1778 -0.2794)
						)
						(arc
							(start 0.1778 -0.2794)
							(mid 0.249642 -0.249642)
							(end 0.2794 -0.1778)
						)
						(arc
							(start 0.2794 0.1778)
							(mid 0.249642 0.249642)
							(end 0.1778 0.2794)
						)
					)
					(width 0)
					(fill yes)
				)
			)
		)
		(pad "2" smd custom
			(at 0 0.4445 90)
			(size 0.1397 0.1397)
			(layers "B.Cu" "B.Mask" "B.Paste")
			(net "TCA9555_A1")
			(options
				(clearance outline)
				(anchor circle)
			)
			(primitives
				(gr_poly
					(pts
						(arc
							(start -0.1778 0.2794)
							(mid -0.249642 0.249642)
							(end -0.2794 0.1778)
						)
						(arc
							(start -0.2794 -0.1778)
							(mid -0.249642 -0.249642)
							(end -0.1778 -0.2794)
						)
						(arc
							(start 0.1778 -0.2794)
							(mid 0.249642 -0.249642)
							(end 0.2794 -0.1778)
						)
						(arc
							(start 0.2794 0.1778)
							(mid 0.249642 0.249642)
							(end 0.1778 0.2794)
						)
					)
					(width 0)
					(fill yes)
				)
			)
		)
	)
	(footprint ""
		(layer "B.Cu")
		(at 45.1485 -153.2255)
		(property "Reference" "TP190"
			(at 0 0 0)
			(layer "B.SilkS")
			(hide yes)
			(effects
				(font
					(size 1.27 1.27)
				)
				(justify mirror)
			)
		)
		(property "Value" "TPAD28-2-GP"
			(at 0.0127 -1.6637 0)
			(unlocked yes)
			(layer "B.Fab")
			(hide yes)
			(effects
				(font
					(size 1.016 1.016)
					(thickness 0.1524)
				)
				(justify mirror)
			)
		)
		(property "Device Type" "TPAD28"
			(at 0.0127 -3.1877 0)
			(unlocked yes)
			(layer "B.Fab")
			(hide yes)
			(effects
				(font
					(size 1.016 1.016)
					(thickness 0.1524)
				)
				(justify mirror)
			)
		)
		(duplicate_pad_numbers_are_jumpers no)
		(fp_poly
			(pts
				(arc
					(start 0.3556 0)
					(mid -0.3556 0)
					(end 0.3556 0)
				)
			)
			(stroke
				(width 0)
				(type default)
			)
			(fill no)
			(layer "B.CrtYd")
		)
		(fp_poly
			(pts
				(arc
					(start 0.6096 0)
					(mid -0.6096 0)
					(end 0.6096 0)
				)
			)
			(stroke
				(width 0)
				(type default)
			)
			(fill no)
			(layer "B.Fab")
		)
		(pad "1" smd circle
			(at 0 0 180)
			(size 0.7112 0.7112)
			(layers "B.Cu" "B.Mask" "B.Paste")
			(net "TP_BMC_GPIOL4")
		)
	)
	(footprint ""
		(layer "B.Cu")
		(at 38.45179 -119.014748 -90)
		(property "Reference" "R285"
			(at 0 0 90)
			(layer "B.SilkS")
			(hide yes)
			(effects
				(font
					(size 1.27 1.27)
				)
				(justify mirror)
			)
		)
		(property "Value" "4K7R2F-GP"
			(at -0.064008 -3.993896 270)
			(unlocked yes)
			(layer "B.Fab")
			(hide yes)
			(effects
				(font
					(size 1.016 1.016)
					(thickness 0.1524)
				)
				(justify mirror)
			)
		)
		(property "Device Type" "R402H16"
			(at -0.064008 -5.517896 270)
			(unlocked yes)
			(layer "B.Fab")
			(hide yes)
			(effects
				(font
					(size 1.016 1.016)
					(thickness 0.1524)
				)
				(justify mirror)
			)
		)
		(duplicate_pad_numbers_are_jumpers no)
		(fp_line
			(start -0.508 -0.9398)
			(end 0.508 -0.9398)
			(stroke
				(width 0.1524)
				(type default)
			)
			(layer "B.SilkS")
		)
		(fp_line
			(start 0.508 -0.9398)
			(end 0.508 0.9398)
			(stroke
				(width 0.1524)
				(type default)
			)
			(layer "B.SilkS")
		)
		(fp_rect
			(start 0.508 0.9398)
			(end -0.508 -0.9398)
			(stroke
				(width 0)
				(type default)
			)
			(fill no)
			(layer "B.CrtYd")
		)
		(fp_rect
			(start 0.508 0.9398)
			(end -0.508 -0.9398)
			(stroke
				(width 0)
				(type default)
			)
			(fill no)
			(layer "B.Fab")
		)
		(pad "1" smd custom
			(at 0 -0.4445 90)
			(size 0.1397 0.1397)
			(layers "B.Cu" "B.Mask" "B.Paste")
			(net "TEMP_3_A1")
			(options
				(clearance outline)
				(anchor circle)
			)
			(primitives
				(gr_poly
					(pts
						(arc
							(start -0.1778 0.2794)
							(mid -0.249642 0.249642)
							(end -0.2794 0.1778)
						)
						(arc
							(start -0.2794 -0.1778)
							(mid -0.249642 -0.249642)
							(end -0.1778 -0.2794)
						)
						(arc
							(start 0.1778 -0.2794)
							(mid 0.249642 -0.249642)
							(end 0.2794 -0.1778)
						)
						(arc
							(start 0.2794 0.1778)
							(mid 0.249642 0.249642)
							(end 0.1778 0.2794)
						)
					)
					(width 0)
					(fill yes)
				)
			)
		)
		(pad "2" smd custom
			(at 0 0.4445 90)
			(size 0.1397 0.1397)
			(layers "B.Cu" "B.Mask" "B.Paste")
			(net "GND")
			(options
				(clearance outline)
				(anchor circle)
			)
			(primitives
				(gr_poly
					(pts
						(arc
							(start -0.1778 0.2794)
							(mid -0.249642 0.249642)
							(end -0.2794 0.1778)
						)
						(arc
							(start -0.2794 -0.1778)
							(mid -0.249642 -0.249642)
							(end -0.1778 -0.2794)
						)
						(arc
							(start 0.1778 -0.2794)
							(mid 0.249642 -0.249642)
							(end 0.2794 -0.1778)
						)
						(arc
							(start 0.2794 0.1778)
							(mid 0.249642 0.249642)
							(end 0.1778 0.2794)
						)
					)
					(width 0)
					(fill yes)
				)
			)
		)
	)
)
